(kicad_pcb
	(version 20260206)
	(generator "pcbnew")
	(generator_version "10.0")
	(general
		(thickness 1.6)
		(legacy_teardrops no)
	)
	(paper "A4")
	(title_block
		(title "04192023_DAF0TMB3IC0_F0TG_MB_C_brd_V02_OCP.brd")
		(comment 1 "Grand Teton / footprints 7271-7278 of 8354")
	)
	(layers
		(0 "F.Cu" signal "TOP")
		(4 "In1.Cu" signal "GND")
		(6 "In2.Cu" signal "IN1")
		(8 "In3.Cu" signal "GND1")
		(10 "In4.Cu" signal "IN2")
		(12 "In5.Cu" signal "GND2")
		(14 "In6.Cu" signal "IN3")
		(16 "In7.Cu" signal "GND3")
		(18 "In8.Cu" signal "VCC")
		(20 "In9.Cu" signal "VCC1")
		(22 "In10.Cu" signal "GND4")
		(24 "In11.Cu" signal "IN4")
		(26 "In12.Cu" signal "GND5")
		(28 "In13.Cu" signal "IN5")
		(30 "In14.Cu" signal "GND6")
		(32 "In15.Cu" signal "IN6")
		(34 "In16.Cu" signal "GND7")
		(2 "B.Cu" signal "BOTTOM")
		(9 "F.Adhes" user "F.Adhesive")
		(11 "B.Adhes" user "B.Adhesive")
		(13 "F.Paste" user "Package Geometry/Pastemask Top")
		(15 "B.Paste" user "Package Geometry/Pastemask Bottom")
		(5 "F.SilkS" user "Ref Des/Silkscreen Top")
		(7 "B.SilkS" user "Ref Des/Silkscreen Bottom")
		(1 "F.Mask" user "Board Geometry/Soldermask Top")
		(3 "B.Mask" user "Board Geometry/Soldermask Bottom")
		(17 "Dwgs.User" user "User.Drawings")
		(19 "Cmts.User" user "User.Comments")
		(21 "Eco1.User" user "User.Eco1")
		(23 "Eco2.User" user "User.Eco2")
		(25 "Edge.Cuts" user "Board Geometry/Outline")
		(27 "Margin" user)
		(31 "F.CrtYd" user "Package Geometry/Place Bound Top")
		(29 "B.CrtYd" user "Package Geometry/Place Bound Bottom")
		(35 "F.Fab" user "Ref Des/Assembly Top")
		(33 "B.Fab" user "Ref Des/Assembly Bottom")
	)
	(footprint ""
		(layer "B.Cu")
		(at 318.467486 -416.899344 90)
		(property "Reference" "C6541"
			(at 0 0 90)
			(layer "B.SilkS")
			(hide yes)
			(effects
				(font
					(size 1.27 1.27)
				)
				(justify mirror)
			)
		)
		(property "Value" ""
			(at 0 0 90)
			(layer "B.Fab")
			(effects
				(font
					(size 1.27 1.27)
				)
				(justify mirror)
			)
		)
		(duplicate_pad_numbers_are_jumpers no)
		(fp_line
			(start 0.299974 -0.150114)
			(end -0.299974 -0.150114)
			(stroke
				(width 0.1)
				(type default)
			)
			(layer "B.Fab")
		)
		(fp_line
			(start -0.299974 -0.150114)
			(end -0.299974 0.150114)
			(stroke
				(width 0.1)
				(type default)
			)
			(layer "B.Fab")
		)
		(fp_line
			(start 0.299974 0.150114)
			(end 0.299974 -0.150114)
			(stroke
				(width 0.1)
				(type default)
			)
			(layer "B.Fab")
		)
		(fp_line
			(start -0.299974 0.150114)
			(end 0.299974 0.150114)
			(stroke
				(width 0.1)
				(type default)
			)
			(layer "B.Fab")
		)
		(pad "1" smd rect
			(at 0.2667 0 270)
			(size 0.3048 0.381)
			(layers "B.Cu" "B.Mask" "B.Paste")
			(net "P5E_CPU0_P1_TX_BUF_C_DP<4>")
		)
		(pad "2" smd rect
			(at -0.2667 0 270)
			(size 0.3048 0.381)
			(layers "B.Cu" "B.Mask" "B.Paste")
			(net "P5E_CPU0_P1_TX_BUF_DP<4>")
		)
	)
	(footprint ""
		(layer "B.Cu")
		(at 420.51478 -359.736136)
		(property "Reference" "PR412"
			(at 0 0 0)
			(layer "B.SilkS")
			(hide yes)
			(effects
				(font
					(size 1.27 1.27)
				)
				(justify mirror)
			)
		)
		(property "Value" ""
			(at 0 0 0)
			(layer "B.Fab")
			(effects
				(font
					(size 1.27 1.27)
				)
				(justify mirror)
			)
		)
		(duplicate_pad_numbers_are_jumpers no)
		(fp_line
			(start -0.7874 -0.4064)
			(end -0.7874 0.4064)
			(stroke
				(width 0.1524)
				(type default)
			)
			(layer "B.SilkS")
		)
		(fp_line
			(start -0.7874 0.4064)
			(end 0.7874 0.4064)
			(stroke
				(width 0.1524)
				(type default)
			)
			(layer "B.SilkS")
		)
		(fp_line
			(start 0.7874 -0.4064)
			(end -0.7874 -0.4064)
			(stroke
				(width 0.1524)
				(type default)
			)
			(layer "B.SilkS")
		)
		(fp_line
			(start 0.7874 0.4064)
			(end 0.7874 -0.4064)
			(stroke
				(width 0.1524)
				(type default)
			)
			(layer "B.SilkS")
		)
		(fp_line
			(start -0.67945 -0.3048)
			(end -0.67945 0.3048)
			(stroke
				(width 0.1)
				(type default)
			)
			(layer "B.Fab")
		)
		(fp_line
			(start -0.67945 0.3048)
			(end -0.120396 0.3048)
			(stroke
				(width 0.1)
				(type default)
			)
			(layer "B.Fab")
		)
		(fp_line
			(start -0.12065 -0.3048)
			(end -0.67945 -0.3048)
			(stroke
				(width 0.1)
				(type default)
			)
			(layer "B.Fab")
		)
		(fp_line
			(start -0.12065 -0.2794)
			(end -0.12065 -0.3048)
			(stroke
				(width 0.1)
				(type default)
			)
			(layer "B.Fab")
		)
		(fp_line
			(start -0.120396 0.2794)
			(end 0.12065 0.2794)
			(stroke
				(width 0.1)
				(type default)
			)
			(layer "B.Fab")
		)
		(fp_line
			(start -0.120396 0.3048)
			(end -0.120396 0.2794)
			(stroke
				(width 0.1)
				(type default)
			)
			(layer "B.Fab")
		)
		(fp_line
			(start 0.12065 -0.305054)
			(end 0.12065 -0.2794)
			(stroke
				(width 0.1)
				(type default)
			)
			(layer "B.Fab")
		)
		(fp_line
			(start 0.12065 -0.2794)
			(end -0.12065 -0.2794)
			(stroke
				(width 0.1)
				(type default)
			)
			(layer "B.Fab")
		)
		(fp_line
			(start 0.12065 0.2794)
			(end 0.12065 0.3048)
			(stroke
				(width 0.1)
				(type default)
			)
			(layer "B.Fab")
		)
		(fp_line
			(start 0.12065 0.3048)
			(end 0.67945 0.3048)
			(stroke
				(width 0.1)
				(type default)
			)
			(layer "B.Fab")
		)
		(fp_line
			(start 0.67945 -0.305054)
			(end 0.12065 -0.305054)
			(stroke
				(width 0.1)
				(type default)
			)
			(layer "B.Fab")
		)
		(fp_line
			(start 0.67945 0.3048)
			(end 0.67945 -0.305054)
			(stroke
				(width 0.1)
				(type default)
			)
			(layer "B.Fab")
		)
		(pad "1" smd circle
			(at 0.40005 0 180)
			(size 0 0)
			(layers "B.Cu" "B.Mask" "B.Paste")
			(net "PVDD11_S3_P0_TEMP1")
		)
		(pad "2" smd circle
			(at -0.40005 0 180)
			(size 0 0)
			(layers "B.Cu" "B.Mask" "B.Paste")
			(net "GND")
		)
	)
	(footprint ""
		(layer "B.Cu")
		(at 160.200086 -408.517344 90)
		(property "Reference" "C6753"
			(at 0 0 90)
			(layer "B.SilkS")
			(hide yes)
			(effects
				(font
					(size 1.27 1.27)
				)
				(justify mirror)
			)
		)
		(property "Value" ""
			(at 0 0 90)
			(layer "B.Fab")
			(effects
				(font
					(size 1.27 1.27)
				)
				(justify mirror)
			)
		)
		(duplicate_pad_numbers_are_jumpers no)
		(fp_line
			(start 0.299974 -0.150114)
			(end -0.299974 -0.150114)
			(stroke
				(width 0.1)
				(type default)
			)
			(layer "B.Fab")
		)
		(fp_line
			(start -0.299974 -0.150114)
			(end -0.299974 0.150114)
			(stroke
				(width 0.1)
				(type default)
			)
			(layer "B.Fab")
		)
		(fp_line
			(start 0.299974 0.150114)
			(end 0.299974 -0.150114)
			(stroke
				(width 0.1)
				(type default)
			)
			(layer "B.Fab")
		)
		(fp_line
			(start -0.299974 0.150114)
			(end 0.299974 0.150114)
			(stroke
				(width 0.1)
				(type default)
			)
			(layer "B.Fab")
		)
		(pad "1" smd rect
			(at 0.2667 0 270)
			(size 0.3048 0.381)
			(layers "B.Cu" "B.Mask" "B.Paste")
			(net "P5E_CPU1_P3_TX_BUF_C_DP<14>")
		)
		(pad "2" smd rect
			(at -0.2667 0 270)
			(size 0.3048 0.381)
			(layers "B.Cu" "B.Mask" "B.Paste")
			(net "P5E_CPU1_P3_TX_BUF_DP<14>")
		)
	)
	(footprint ""
		(layer "B.Cu")
		(at 168.44645 -424.117262 -90)
		(property "Reference" "U41"
			(at -3.056128 0.105918 0)
			(unlocked yes)
			(layer "B.SilkS")
			(effects
				(font
					(size 0.7874 0.5842)
					(thickness 0.1524)
				)
				(justify mirror)
			)
		)
		(property "Value" ""
			(at 0 0 90)
			(layer "B.Fab")
			(effects
				(font
					(size 1.27 1.27)
				)
				(justify mirror)
			)
		)
		(duplicate_pad_numbers_are_jumpers no)
		(fp_line
			(start -1.03378 1.284478)
			(end 1.03378 1.284478)
			(stroke
				(width 0.1524)
				(type default)
			)
			(layer "B.SilkS")
		)
		(fp_line
			(start 1.03378 1.284478)
			(end 1.03378 -1.284478)
			(stroke
				(width 0.1524)
				(type default)
			)
			(layer "B.SilkS")
		)
		(fp_line
			(start -1.03378 -1.284478)
			(end -1.03378 1.284478)
			(stroke
				(width 0.1524)
				(type default)
			)
			(layer "B.SilkS")
		)
		(fp_line
			(start 1.03378 -1.284478)
			(end -1.03378 -1.284478)
			(stroke
				(width 0.1524)
				(type default)
			)
			(layer "B.SilkS")
		)
		(fp_poly
			(pts
				(xy 1.258316 -1.470152) (xy 1.86182 -1.775714) (xy 1.375918 -2.13614)
			)
			(stroke
				(width 0)
				(type default)
			)
			(fill yes)
			(layer "B.SilkS")
		)
		(fp_line
			(start -0.774954 1.02489)
			(end 0.774954 1.02489)
			(stroke
				(width 0.1)
				(type default)
			)
			(layer "B.Fab")
		)
		(fp_line
			(start 0.774954 1.02489)
			(end 0.774954 -1.02489)
			(stroke
				(width 0.1)
				(type default)
			)
			(layer "B.Fab")
		)
		(fp_line
			(start -0.774954 -1.02489)
			(end -0.774954 1.02489)
			(stroke
				(width 0.1)
				(type default)
			)
			(layer "B.Fab")
		)
		(fp_line
			(start 0.774954 -1.02489)
			(end -0.774954 -1.02489)
			(stroke
				(width 0.1)
				(type default)
			)
			(layer "B.Fab")
		)
		(fp_poly
			(pts
				(xy 1.201674 -0.750062) (xy 1.806702 -0.447548) (xy 1.806702 -1.052576)
			)
			(stroke
				(width 0)
				(type default)
			)
			(fill yes)
			(layer "B.Fab")
		)
		(pad "1" smd rect
			(at 0.64008 -0.750062)
			(size 0.3048 0.5334)
			(layers "B.Cu" "B.Mask" "B.Paste")
			(net "SMB_RT_CPU1_P3_ROM_MUX_1D_SCL")
		)
		(pad "2" smd rect
			(at 0.64008 -0.249936)
			(size 0.254 0.5334)
			(layers "B.Cu" "B.Mask" "B.Paste")
			(net "SMB_RT_CPU1_P3_ROM_MUX_1D_SDA")
		)
		(pad "3" smd rect
			(at 0.64008 0.249936)
			(size 0.254 0.5334)
			(layers "B.Cu" "B.Mask" "B.Paste")
			(net "SMB_RT_CPU1_P3_ROM_MUX_2D_SCL")
		)
		(pad "4" smd rect
			(at 0.64008 0.750062)
			(size 0.3048 0.5334)
			(layers "B.Cu" "B.Mask" "B.Paste")
			(net "SMB_RT_CPU1_P3_ROM_MUX_2D_SDA")
		)
		(pad "5" smd rect
			(at 0 0.839978 90)
			(size 0.3302 0.635)
			(layers "B.Cu" "B.Mask" "B.Paste")
			(net "GND")
		)
		(pad "6" smd rect
			(at -0.64008 0.750062)
			(size 0.3048 0.5334)
			(layers "B.Cu" "B.Mask" "B.Paste")
			(net "RT_ROM_MUX3_OE_N")
		)
		(pad "7" smd rect
			(at -0.64008 0.249936)
			(size 0.254 0.5334)
			(layers "B.Cu" "B.Mask" "B.Paste")
			(net "SMB_RT_CPU1_P3_ROM_R_SDA")
		)
		(pad "8" smd rect
			(at -0.64008 -0.249936)
			(size 0.254 0.5334)
			(layers "B.Cu" "B.Mask" "B.Paste")
			(net "SMB_RT_CPU1_P3_ROM_R_SCL")
		)
		(pad "9" smd rect
			(at -0.64008 -0.750062)
			(size 0.3048 0.5334)
			(layers "B.Cu" "B.Mask" "B.Paste")
			(net "FM_SMB_RT_ROM_MUX3_SEL")
		)
		(pad "10" smd rect
			(at 0 -0.839978 90)
			(size 0.3302 0.635)
			(layers "B.Cu" "B.Mask" "B.Paste")
			(net "P3V3_AUX")
		)
	)
	(footprint ""
		(layer "B.Cu")
		(at 389.683752 -395.148562 90)
		(property "Reference" "C1046"
			(at 0 0 90)
			(layer "B.SilkS")
			(hide yes)
			(effects
				(font
					(size 1.27 1.27)
				)
				(justify mirror)
			)
		)
		(property "Value" ""
			(at 0 0 90)
			(layer "B.Fab")
			(effects
				(font
					(size 1.27 1.27)
				)
				(justify mirror)
			)
		)
		(duplicate_pad_numbers_are_jumpers no)
		(fp_line
			(start 0.299974 -0.150114)
			(end -0.299974 -0.150114)
			(stroke
				(width 0.1)
				(type default)
			)
			(layer "B.Fab")
		)
		(fp_line
			(start -0.299974 -0.150114)
			(end -0.299974 0.150114)
			(stroke
				(width 0.1)
				(type default)
			)
			(layer "B.Fab")
		)
		(fp_line
			(start 0.299974 0.150114)
			(end 0.299974 -0.150114)
			(stroke
				(width 0.1)
				(type default)
			)
			(layer "B.Fab")
		)
		(fp_line
			(start -0.299974 0.150114)
			(end 0.299974 0.150114)
			(stroke
				(width 0.1)
				(type default)
			)
			(layer "B.Fab")
		)
		(pad "1" smd rect
			(at 0.2667 0 270)
			(size 0.3048 0.381)
			(layers "B.Cu" "B.Mask" "B.Paste")
			(net "P0V9_CPU0_RT3_2A")
		)
		(pad "2" smd rect
			(at -0.2667 0 270)
			(size 0.3048 0.381)
			(layers "B.Cu" "B.Mask" "B.Paste")
			(net "GND")
		)
	)
	(footprint ""
		(layer "B.Cu")
		(at 365.835692 -258.405122)
		(property "Reference" "C2559"
			(at 0 0 0)
			(layer "B.SilkS")
			(hide yes)
			(effects
				(font
					(size 1.27 1.27)
				)
				(justify mirror)
			)
		)
		(property "Value" ""
			(at 0 0 0)
			(layer "B.Fab")
			(effects
				(font
					(size 1.27 1.27)
				)
				(justify mirror)
			)
		)
		(duplicate_pad_numbers_are_jumpers no)
		(fp_line
			(start -0.7874 -0.4064)
			(end -0.7874 0.4064)
			(stroke
				(width 0.1524)
				(type default)
			)
			(layer "B.SilkS")
		)
		(fp_line
			(start -0.7874 0.4064)
			(end 0.7874 0.4064)
			(stroke
				(width 0.1524)
				(type default)
			)
			(layer "B.SilkS")
		)
		(fp_line
			(start 0.7874 -0.4064)
			(end -0.7874 -0.4064)
			(stroke
				(width 0.1524)
				(type default)
			)
			(layer "B.SilkS")
		)
		(fp_line
			(start 0.7874 0.4064)
			(end 0.7874 -0.4064)
			(stroke
				(width 0.1524)
				(type default)
			)
			(layer "B.SilkS")
		)
		(fp_line
			(start -0.67945 -0.3048)
			(end -0.67945 0.3048)
			(stroke
				(width 0.1)
				(type default)
			)
			(layer "B.Fab")
		)
		(fp_line
			(start -0.67945 0.3048)
			(end -0.120396 0.3048)
			(stroke
				(width 0.1)
				(type default)
			)
			(layer "B.Fab")
		)
		(fp_line
			(start -0.12065 -0.3048)
			(end -0.67945 -0.3048)
			(stroke
				(width 0.1)
				(type default)
			)
			(layer "B.Fab")
		)
		(fp_line
			(start -0.12065 -0.2794)
			(end -0.12065 -0.3048)
			(stroke
				(width 0.1)
				(type default)
			)
			(layer "B.Fab")
		)
		(fp_line
			(start -0.120396 0.2794)
			(end 0.12065 0.2794)
			(stroke
				(width 0.1)
				(type default)
			)
			(layer "B.Fab")
		)
		(fp_line
			(start -0.120396 0.3048)
			(end -0.120396 0.2794)
			(stroke
				(width 0.1)
				(type default)
			)
			(layer "B.Fab")
		)
		(fp_line
			(start 0.12065 -0.305054)
			(end 0.12065 -0.2794)
			(stroke
				(width 0.1)
				(type default)
			)
			(layer "B.Fab")
		)
		(fp_line
			(start 0.12065 -0.2794)
			(end -0.12065 -0.2794)
			(stroke
				(width 0.1)
				(type default)
			)
			(layer "B.Fab")
		)
		(fp_line
			(start 0.12065 0.2794)
			(end 0.12065 0.3048)
			(stroke
				(width 0.1)
				(type default)
			)
			(layer "B.Fab")
		)
		(fp_line
			(start 0.12065 0.3048)
			(end 0.67945 0.3048)
			(stroke
				(width 0.1)
				(type default)
			)
			(layer "B.Fab")
		)
		(fp_line
			(start 0.67945 -0.305054)
			(end 0.12065 -0.305054)
			(stroke
				(width 0.1)
				(type default)
			)
			(layer "B.Fab")
		)
		(fp_line
			(start 0.67945 0.3048)
			(end 0.67945 -0.305054)
			(stroke
				(width 0.1)
				(type default)
			)
			(layer "B.Fab")
		)
		(pad "1" smd circle
			(at 0.40005 0 180)
			(size 0 0)
			(layers "B.Cu" "B.Mask" "B.Paste")
			(net "PVDDCR_SOC_P0")
		)
		(pad "2" smd circle
			(at -0.40005 0 180)
			(size 0 0)
			(layers "B.Cu" "B.Mask" "B.Paste")
			(net "GND")
		)
	)
	(footprint ""
		(layer "B.Cu")
		(at 373.329454 -255.84531)
		(property "Reference" "C2578"
			(at 0 0 0)
			(layer "B.SilkS")
			(hide yes)
			(effects
				(font
					(size 1.27 1.27)
				)
				(justify mirror)
			)
		)
		(property "Value" ""
			(at 0 0 0)
			(layer "B.Fab")
			(effects
				(font
					(size 1.27 1.27)
				)
				(justify mirror)
			)
		)
		(duplicate_pad_numbers_are_jumpers no)
		(fp_line
			(start -0.7874 -0.4064)
			(end -0.7874 0.4064)
			(stroke
				(width 0.1524)
				(type default)
			)
			(layer "B.SilkS")
		)
		(fp_line
			(start -0.7874 0.4064)
			(end 0.7874 0.4064)
			(stroke
				(width 0.1524)
				(type default)
			)
			(layer "B.SilkS")
		)
		(fp_line
			(start 0.7874 -0.4064)
			(end -0.7874 -0.4064)
			(stroke
				(width 0.1524)
				(type default)
			)
			(layer "B.SilkS")
		)
		(fp_line
			(start 0.7874 0.4064)
			(end 0.7874 -0.4064)
			(stroke
				(width 0.1524)
				(type default)
			)
			(layer "B.SilkS")
		)
		(fp_line
			(start -0.67945 -0.3048)
			(end -0.67945 0.3048)
			(stroke
				(width 0.1)
				(type default)
			)
			(layer "B.Fab")
		)
		(fp_line
			(start -0.67945 0.3048)
			(end -0.120396 0.3048)
			(stroke
				(width 0.1)
				(type default)
			)
			(layer "B.Fab")
		)
		(fp_line
			(start -0.12065 -0.3048)
			(end -0.67945 -0.3048)
			(stroke
				(width 0.1)
				(type default)
			)
			(layer "B.Fab")
		)
		(fp_line
			(start -0.12065 -0.2794)
			(end -0.12065 -0.3048)
			(stroke
				(width 0.1)
				(type default)
			)
			(layer "B.Fab")
		)
		(fp_line
			(start -0.120396 0.2794)
			(end 0.12065 0.2794)
			(stroke
				(width 0.1)
				(type default)
			)
			(layer "B.Fab")
		)
		(fp_line
			(start -0.120396 0.3048)
			(end -0.120396 0.2794)
			(stroke
				(width 0.1)
				(type default)
			)
			(layer "B.Fab")
		)
		(fp_line
			(start 0.12065 -0.305054)
			(end 0.12065 -0.2794)
			(stroke
				(width 0.1)
				(type default)
			)
			(layer "B.Fab")
		)
		(fp_line
			(start 0.12065 -0.2794)
			(end -0.12065 -0.2794)
			(stroke
				(width 0.1)
				(type default)
			)
			(layer "B.Fab")
		)
		(fp_line
			(start 0.12065 0.2794)
			(end 0.12065 0.3048)
			(stroke
				(width 0.1)
				(type default)
			)
			(layer "B.Fab")
		)
		(fp_line
			(start 0.12065 0.3048)
			(end 0.67945 0.3048)
			(stroke
				(width 0.1)
				(type default)
			)
			(layer "B.Fab")
		)
		(fp_line
			(start 0.67945 -0.305054)
			(end 0.12065 -0.305054)
			(stroke
				(width 0.1)
				(type default)
			)
			(layer "B.Fab")
		)
		(fp_line
			(start 0.67945 0.3048)
			(end 0.67945 -0.305054)
			(stroke
				(width 0.1)
				(type default)
			)
			(layer "B.Fab")
		)
		(pad "1" smd circle
			(at 0.40005 0 180)
			(size 0 0)
			(layers "B.Cu" "B.Mask" "B.Paste")
			(net "PVDDCR_SOC_P0")
		)
		(pad "2" smd circle
			(at -0.40005 0 180)
			(size 0 0)
			(layers "B.Cu" "B.Mask" "B.Paste")
			(net "GND")
		)
	)
	(footprint ""
		(layer "B.Cu")
		(at 88.243918 -335.04632 90)
		(property "Reference" "PC381_1"
			(at 0 0 90)
			(layer "B.SilkS")
			(hide yes)
			(effects
				(font
					(size 1.27 1.27)
				)
				(justify mirror)
			)
		)
		(property "Value" ""
			(at 0 0 90)
			(layer "B.Fab")
			(effects
				(font
					(size 1.27 1.27)
				)
				(justify mirror)
			)
		)
		(duplicate_pad_numbers_are_jumpers no)
		(fp_line
			(start 1.524 -0.762)
			(end -1.524 -0.762)
			(stroke
				(width 0.1524)
				(type default)
			)
			(layer "B.SilkS")
		)
		(fp_line
			(start -1.524 -0.762)
			(end -1.524 0.762)
			(stroke
				(width 0.1524)
				(type default)
			)
			(layer "B.SilkS")
		)
		(fp_line
			(start 1.524 0.762)
			(end 1.524 -0.762)
			(stroke
				(width 0.1524)
				(type default)
			)
			(layer "B.SilkS")
		)
		(fp_line
			(start -1.524 0.762)
			(end 1.524 0.762)
			(stroke
				(width 0.1524)
				(type default)
			)
			(layer "B.SilkS")
		)
		(fp_line
			(start 1.1049 -0.724916)
			(end 1.1049 0.724916)
			(stroke
				(width 0.1)
				(type default)
			)
			(layer "B.Fab")
		)
		(fp_line
			(start -1.1049 -0.724916)
			(end 1.1049 -0.724916)
			(stroke
				(width 0.1)
				(type default)
			)
			(layer "B.Fab")
		)
		(fp_line
			(start 1.1049 0.724916)
			(end -1.1049 0.724916)
			(stroke
				(width 0.1)
				(type default)
			)
			(layer "B.Fab")
		)
		(fp_line
			(start -1.1049 0.724916)
			(end -1.1049 -0.724916)
			(stroke
				(width 0.1)
				(type default)
			)
			(layer "B.Fab")
		)
		(pad "1" smd rect
			(at 0.889 0 90)
			(size 1.016 1.27)
			(layers "B.Cu" "B.Mask" "B.Paste")
			(net "SW_P12V_AUX_PVDDCR_CPU1_P1_FLT")
		)
		(pad "2" smd rect
			(at -0.889 0 90)
			(size 1.016 1.27)
			(layers "B.Cu" "B.Mask" "B.Paste")
			(net "GND")
		)
	)
)
